FILE_TYPE = CONNECTIVITY;
{Allegro Design Entry HDL 16.6-p007 (v16-6-112F) 10/10/2012}
"PAGE_NUMBER" = 227;
0"NC";
1"PVDDQ_KLM\g";
2"GND\g";
3"GND\g";
4"P5V_STBY\g";
5"GND\g";
6"GND\g";
7"GND\g";
8"GND\g";
9"GND\g";
10"GND\g";
11"GND\g";
12"GND\g";
13"PVDDQ_KLM\g";
14"GND\g";
15"GND\g";
16"GND\g";
17"VR_FET_SW_P12V_STBY_PVDDQ_KLM\g";
18"GND\g";
19"VR_FET_SW_P12V_STBY_PVDDQ_KLM\g";
20"P5V_STBY\g";
21"VR_PVDDQ_KLM_PH2_SW";
22"VR_PVDDQ_KLM_PH2_VCIN";
23"VR_PVDDQ_KLM_PWM2";
24"VR_PVDDQ_KLM_PH1_PHASE";
25"NC_PVDDQ_KLM_PH2_P31";
26"VR_PVDDQ_KLM_PH2_BOOT_R";
27"VR_PVDDQ_KLM_PH2_PHASE";
28"VR_PVDDQ_KLM_PH2_OCSET"VOLTAGE"3.6";
29"A_TSENSE_PVDDQ_KLM";
30"VR_PVDDQ_KLM_AIREF2";
31"TP_PVDDQ_KLM_PH2_GL_1";
32"TP_PVDDQ_KLM_PH2_GL_0";
33"VR_PVDDQ_KLM_PH2_BOOT";
34"VR_PVDDQ_KLM_PH1_BOOT_R";
35"A_TSENSE_PVDDQ_KLM";
36"VR_PVDDQ_KLM_PH1_OCSET"VOLTAGE"3.6";
37"VR_PVDDQ_KLM_PH1_BOOT";
38"VR_PVDDQ_KLM_PWM1";
39"UN$227$3D01R5F-GP$I125$1";
40"VR_PVDDQ_KLM_PH1_SW";
41"VR_PVDDQ_KLM_AIREF1";
42"ISENSE_PVDDQ_KLM_PH2_IMON";
43"VR_PVDDQ_KLM_PH1_VCIN";
44"TP_PVDDQ_KLM_PH1_GL_1";
45"UN$227$3D01R5F-GP$I124$1";
46"NC_PVDDQ_KLM_PH1_P31";
47"TP_PVDDQ_KLM_PH1_GL_0";
48"ISENSE_PVDDQ_KLM_PH1_IMON";
%"PVDDQ_KLM"
"1","(4025,1950)","0","mstr_symbols","I1";
;
HDL_POWER"PVDDQ_KLM"
BODY_TYPE"PLUMBING"
VOLTAGE"1.2V"
CDS_LIB"mstr_symbols";
"G\NAC"1;
%"IR354XX"
"1","(1500,2150)","0","mstr_discrete","I101";
;
CDS_SEC"1"
CDS_LIB"mstr_discrete"
PACK_TYPE"SM"
SEC_TYPE"SM"
SEC"1"
CDS_LOCATION"EU1A2"
NO_XNET_CONNECTION"1"
MATERIAL"IC"
LOCATION"EU1A2"
VALUE"IR35411"
PART_NUMBER"H73688-001";
"TOUT_FLT"
$PN"36"35;
"NC"
$PN"31"46;
"OCSET"
$PN"37"36;
"IOUT"
$PN"38"48;
"SW"
$PN"10"40;
"BOOST"
$PN"33"34;
"REFIN"
$PN"39"41;
"PWM"
$PN"34"38;
"PHASE"
$PN"32"24;
"VIN<0>"
$PN"25"19;
"VCC"
$PN"3"43;
"VIN<1>"
$PN"30"19;
"EN"
$PN"35"4;
"VDRV"
$PN"4"4;
"VOS"
$PN"1"1;
"LGND"
$PN"2"11;
"PGND<1>"
$PN"7"11;
"PGND<2>"
$PN"40"11;
"PGND<0>"
$PN"5"11;
"GL<0>"
$PN"6"47;
"GL<1>"
$PN"41"44;
%"IR354XX"
"1","(1475,0)","0","mstr_discrete","I102";
;
CDS_SEC"1"
PACK_TYPE"SM"
SEC_TYPE"SM"
SEC"1"
CDS_LOCATION"EU1A1"
CDS_LIB"mstr_discrete"
PART_NUMBER"H73688-001"
NO_XNET_CONNECTION"1"
LOCATION"EU1A1"
MATERIAL"IC"
VALUE"IR35411";
"TOUT_FLT"
$PN"36"29;
"NC"
$PN"31"25;
"OCSET"
$PN"37"28;
"IOUT"
$PN"38"42;
"SW"
$PN"10"21;
"BOOST"
$PN"33"26;
"REFIN"
$PN"39"30;
"PWM"
$PN"34"23;
"PHASE"
$PN"32"27;
"VIN<0>"
$PN"25"17;
"VCC"
$PN"3"22;
"VIN<1>"
$PN"30"17;
"EN"
$PN"35"20;
"VDRV"
$PN"4"20;
"VOS"
$PN"1"13;
"LGND"
$PN"2"16;
"PGND<1>"
$PN"7"16;
"PGND<2>"
$PN"40"16;
"PGND<0>"
$PN"5"16;
"GL<0>"
$PN"6"32;
"GL<1>"
$PN"41"31;
%"RES"
"2","(4325,2325)","0","mstr_discrete","I103";
;
CDS_SEC"1"
CDS_LOCATION"R1A3"
CDS_LIB"mstr_discrete"
SEC"1"
SEC_TYPE"0402"
PACK_TYPE"0402"
MATERIAL"EMPTY"
WATTAGE"1/16W"
TOLERANCE"1%"
LOCATION"R1A3"
VALUE"68.1K"
PART_NUMBER"G21796-187";
"A"
$PN"1"36;
"B"
$PN"2"2;
%"GND"
"1","(4325,2025)","0","mstr_symbols","I104";
;
HDL_POWER"GND"
BODY_TYPE"PLUMBING"
ROOM"PVCCIN_CPU0_PWR_VR"
BOM_COST"PROC_VRD_VCCIN_CPU0"
SIZE"1B"
CDS_LIB"mstr_symbols"
VOLTAGE"0";
"A\NAC"2;
%"RES"
"2","(4300,175)","0","mstr_discrete","I105";
;
CDS_SEC"1"
CDS_LOCATION"R1A2"
SEC_TYPE"0402"
SEC"1"
CDS_LIB"mstr_discrete"
LOCATION"R1A2"
VALUE"68.1K"
TOLERANCE"1%"
PACK_TYPE"0402"
WATTAGE"1/16W"
PART_NUMBER"G21796-187"
MATERIAL"EMPTY";
"A"
$PN"1"28;
"B"
$PN"2"3;
%"GND"
"1","(4300,-125)","0","mstr_symbols","I106";
;
HDL_POWER"GND"
BODY_TYPE"PLUMBING"
SIZE"1B"
VOLTAGE"0"
CDS_LIB"mstr_symbols"
BOM_COST"PROC_VRD_VCCIN_CPU0"
ROOM"PVCCIN_CPU0_PWR_VR";
"A\NAC"3;
%"P5V_STBY"
"1","(250,3125)","0","mstr_symbols","I107";
;
HDL_POWER"P5V_STBY"
BODY_TYPE"PLUMBING"
SIZE"1B"
CDS_LIB"mstr_symbols"
VOLTAGE"5.0V";
"G\NAC"4;
%"CAP_A"
"1","(825,1650)","0","dev_discrete","I109";
;
CDS_SEC"1"
$SEC"1"
CDS_LOCATION"CT7"
ROOM"PVCCIN_CPU0_PWR_VR"
CDS_LIB"dev_discrete"
STATUS"NOPOP"
VALUE"0.1UF"
LOCATION"CT7"
MATERIAL"X7R"
TOLERANCE"10%"
VOLTAGE"16V"
PART_NUMBER"A36096-030"
PACK_TYPE"0402V";
"B"
$PN"2"5;
"A"
$PN"1"41;
%"GND"
"1","(825,1400)","0","mstr_symbols","I110";
;
HDL_POWER"GND"
BODY_TYPE"PLUMBING"
ROOM"PVCCIN_CPU0_PWR_VR"
BOM_COST"PROC_VRD_VCCIN_CPU0"
SIZE"1B"
VOLTAGE"0"
CDS_LIB"mstr_symbols";
"A\NAC"5;
%"SC2K2P50V3KX-GP"
"1","(2600,1700)","0","w_hdl","I111";
;
CDS_SEC"1"
$SEC"1"
CDS_LOCATION"CT9"
CDS_LIB"w_hdl"
CDS_LMAN_SYM_OUTLINE"-50,25,50,-25"
PART_NUMBER"78.22224.2BL"
PACK_TYPE"SMD-BCG6"
VALUE"SC2K2P50V3KX-GP"
STATUS"NOPOP"
LOCATION"CT9";
"2"
$PN"2"39;
"1"
$PN"1"40;
%"GND"
"1","(2600,1150)","0","mstr_symbols","I113";
;
HDL_POWER"GND"
BODY_TYPE"PLUMBING"
ROOM"PVCCIN_CPU0_PWR_VR"
BOM_COST"PROC_VRD_VCCIN_CPU0"
VOLTAGE"0"
SIZE"1B"
CDS_LIB"mstr_symbols";
"A\NAC"6;
%"CAP"
"1","(2725,2125)","0","mstr_discrete","I114";
;
CDS_SEC"1"
$SEC"1"
CDS_LOCATION"CT8"
CDS_LIB"mstr_discrete"
ROOM"VDDQ_KLM_PWR_VR"
STATUS"NOPOP"
PART_NUMBER"A36096-046"
MATERIAL"X7R"
TOLERANCE"10%"
VOLTAGE"50V"
VALUE"1000PF"
LOCATION"CT8"
PACK_TYPE"0402LF";
"A"
$PN"1"35;
"B"
$PN"2"7;
%"GND"
"1","(2725,1925)","0","mstr_symbols","I115";
;
HDL_POWER"GND"
BODY_TYPE"PLUMBING"
CDS_LIB"mstr_symbols"
ROOM"VDDQ_KLM_PWR_VR"
VOLTAGE"0"
SIZE"1B";
"A\NAC"7;
%"SC2K2P50V3KX-GP"
"1","(2575,-425)","0","w_hdl","I116";
;
CDS_SEC"1"
$SEC"1"
CDS_LOCATION"CT11"
PART_NUMBER"78.22224.2BL"
PACK_TYPE"SMD-BCG6"
CDS_LMAN_SYM_OUTLINE"-50,25,50,-25"
CDS_LIB"w_hdl"
LOCATION"CT11"
STATUS"NOPOP"
VALUE"SC2K2P50V3KX-GP";
"2"
$PN"2"45;
"1"
$PN"1"21;
%"GND"
"1","(2575,-975)","0","mstr_symbols","I117";
;
CDS_LIB"mstr_symbols"
SIZE"1B"
VOLTAGE"0"
BOM_COST"PROC_VRD_VCCIN_CPU0"
ROOM"PVCCIN_CPU0_PWR_VR"
BODY_TYPE"PLUMBING"
HDL_POWER"GND";
"A\NAC"8;
%"CAP"
"1","(2600,50)","0","mstr_discrete","I119";
;
CDS_SEC"1"
$SEC"1"
CDS_LOCATION"CT10"
ROOM"VDDQ_KLM_PWR_VR"
CDS_LIB"mstr_discrete"
PART_NUMBER"A36096-046"
MATERIAL"X7R"
VALUE"1000PF"
PACK_TYPE"0402LF"
TOLERANCE"10%"
STATUS"NOPOP"
LOCATION"CT10"
VOLTAGE"50V";
"A"
$PN"1"29;
"B"
$PN"2"9;
%"GND"
"1","(2600,-150)","0","mstr_symbols","I120";
;
HDL_POWER"GND"
BODY_TYPE"PLUMBING"
SIZE"1B"
VOLTAGE"0"
ROOM"VDDQ_KLM_PWR_VR"
CDS_LIB"mstr_symbols";
"A\NAC"9;
%"CAP_A"
"1","(800,-500)","0","dev_discrete","I122";
;
CDS_SEC"1"
$SEC"1"
CDS_LOCATION"CT12"
ROOM"PVCCIN_CPU0_PWR_VR"
CDS_LIB"dev_discrete"
PART_NUMBER"A36096-030"
PACK_TYPE"0402V"
LOCATION"CT12"
VOLTAGE"16V"
TOLERANCE"10%"
MATERIAL"X7R"
VALUE"0.1UF"
STATUS"NOPOP";
"B"
$PN"2"10;
"A"
$PN"1"30;
%"GND"
"1","(800,-750)","0","mstr_symbols","I123";
;
HDL_POWER"GND"
BODY_TYPE"PLUMBING"
ROOM"PVCCIN_CPU0_PWR_VR"
BOM_COST"PROC_VRD_VCCIN_CPU0"
SIZE"1B"
VOLTAGE"0"
CDS_LIB"mstr_symbols";
"A\NAC"10;
%"3D01R5F-GP"
"1","(2575,-750)","0","w_hdl","I124";
;
CDS_SEC"1"
$SEC"1"
CDS_LOCATION"RT7"
CDS_LMAN_SYM_OUTLINE"-50,75,50,-75"
CDS_LIB"w_hdl"
PART_NUMBER"64.3R015.16L"
PACK_TYPE"SMD-RG5"
VALUE"3D01R5F-GP"
STATUS"NOPOP"
LOCATION"RT7";
"2"
$PN"2"8;
"1"
$PN"1"45;
%"3D01R5F-GP"
"1","(2600,1400)","0","w_hdl","I125";
;
CDS_SEC"1"
$SEC"1"
CDS_LOCATION"RT6"
PACK_TYPE"SMD-RG5"
PART_NUMBER"64.3R015.16L"
CDS_LIB"w_hdl"
CDS_LMAN_SYM_OUTLINE"-50,75,50,-75"
VALUE"3D01R5F-GP"
STATUS"NOPOP"
LOCATION"RT6";
"2"
$PN"2"6;
"1"
$PN"1"39;
%"RES"
"1","(-75,1950)","0","mstr_discrete","I126";
;
CDS_SEC"1"
$SEC"1"
CDS_LOCATION"RT5"
CDS_LIB"mstr_discrete"
ROOM"BMC_DEBUG_HEADER"
BOM_COST"DEBUG"
VALUE"0.0"
MATERIAL"CHIP"
TOLERANCE"5%"
PART_NUMBER"G21497-005"
LOCATION"RT5"
WATTAGE"1/16W"
PACK_TYPE"0402";
"B"
$PN"2"34;
"A"
$PN"1"37;
%"RES"
"1","(-200,-225)","0","mstr_discrete","I127";
;
CDS_SEC"1"
$SEC"1"
CDS_LOCATION"RT8"
CDS_LIB"mstr_discrete"
BOM_COST"DEBUG"
ROOM"BMC_DEBUG_HEADER"
VALUE"0.0"
PART_NUMBER"G21497-005"
LOCATION"RT8"
PACK_TYPE"0402"
MATERIAL"CHIP"
TOLERANCE"5%"
WATTAGE"1/16W";
"B"
$PN"2"26;
"A"
$PN"1"33;
%"GND"
"1","(2350,1400)","0","mstr_symbols","I19";
;
HDL_POWER"GND"
BODY_TYPE"PLUMBING"
BOM_COST"VDDQ_KLM_PWR_VR"
ROOM"VDDQ_KLM_PWR_VR"
VOLTAGE"0"
CDS_LIB"mstr_symbols"
SIZE"1B";
"A\NAC"11;
%"GND"
"1","(-2650,2000)","0","mstr_symbols","I35";
;
HDL_POWER"GND"
BODY_TYPE"PLUMBING"
SIZE"1B"
VOLTAGE"0"
CDS_LIB"mstr_symbols"
ROOM"VDDQ_KLM_PWR_VR"
BOM_COST"VDDQ_KLM_PWR_VR";
"A\NAC"12;
%"CAP"
"1","(-950,1850)","2","mstr_discrete","I44";
;
CDS_SEC"1"
CDS_LIB"mstr_discrete"
CDS_LOCATION"C1A18"
ROOM"VDDQ_KLM_PWR_VR"
SEC"1"
SPOF"TRUE"
SEC_TYPE"0402"
MATERIAL"X7R"
TOLERANCE"10%"
PART_NUMBER"A36096-104"
VOLTAGE"16V"
VALUE"0.220UF"
LOCATION"C1A18"
PACK_TYPE"0402";
"A"
$PN"1"37;
"B"
$PN"2"24;
%"CAP"
"1","(-2650,2450)","0","mstr_discrete","I45";
;
CDS_SEC"1"
CDS_LIB"mstr_discrete"
CDS_LOCATION"C9L11"
ROOM"VDDQ_KLM_PWR_VR"
SEC"1"
SEC_TYPE"0805"
MATERIAL"X6S"
VOLTAGE"16V"
PACK_TYPE"0805"
TOLERANCE"10%"
VALUE"10UF"
PART_NUMBER"C95333-007"
LOCATION"C9L11";
"A"
$PN"1"19;
"B"
$PN"2"12;
%"CAP"
"1","(-2400,2400)","0","mstr_discrete","I46";
;
CDS_SEC"1"
CDS_LIB"mstr_discrete"
CDS_LOCATION"C9L10"
ROOM"VDDQ_KLM_PWR_VR"
SEC_TYPE"0805"
SEC"1"
MATERIAL"X6S"
VOLTAGE"16V"
PACK_TYPE"0805"
TOLERANCE"10%"
VALUE"10UF"
PART_NUMBER"C95333-007"
LOCATION"C9L10";
"A"
$PN"1"19;
"B"
$PN"2"12;
%"CAP"
"1","(-2175,2425)","0","mstr_discrete","I47";
;
CDS_SEC"1"
CDS_LIB"mstr_discrete"
CDS_LOCATION"C9L6"
SEC_TYPE"0805"
SEC"1"
ROOM"VDDQ_KLM_PWR_VR"
MATERIAL"X6S"
VOLTAGE"16V"
PACK_TYPE"0805"
TOLERANCE"10%"
VALUE"10UF"
PART_NUMBER"C95333-007"
LOCATION"C9L6";
"A"
$PN"1"19;
"B"
$PN"2"12;
%"CAP"
"1","(-1900,2425)","0","mstr_discrete","I48";
;
CDS_SEC"1"
CDS_LOCATION"C1A19"
CDS_LIB"mstr_discrete"
SEC_TYPE"0402"
SEC"1"
ROOM"VDDQ_KLM_PWR_VR"
MATERIAL"X6S"
VOLTAGE"16V"
PACK_TYPE"0402"
TOLERANCE"10%"
VALUE"1.0UF"
PART_NUMBER"D97712-011"
LOCATION"C1A19";
"A"
$PN"1"19;
"B"
$PN"2"12;
%"CAP"
"1","(-1350,2425)","0","mstr_discrete","I50";
;
CDS_SEC"1"
CDS_LOCATION"C1B20"
CDS_LIB"mstr_discrete"
ROOM"VDDQ_KLM_PWR_VR"
SEC"1"
SEC_TYPE"0402"
LOCATION"C1B20"
MATERIAL"X6S"
VALUE"1.0UF"
TOLERANCE"10%"
VOLTAGE"16V"
PART_NUMBER"D97712-011"
PACK_TYPE"0402";
"A"
$PN"1"43;
"B"
$PN"2"12;
%"CAP_A"
"1","(-1675,2375)","0","dev_discrete","I51";
;
CDS_LOCATION"C1A10"
CDS_LIB"dev_discrete"
CDS_SEC"1"
ROOM"VDDQ_KLM_PWR_VR"
SEC_TYPE"0402V"
SEC"1"
PACK_TYPE"0402V"
VALUE"0.1UF"
LOCATION"C1A10"
PART_NUMBER"A36096-030"
MATERIAL"X7R"
TOLERANCE"10%"
VOLTAGE"16V";
"B"
$PN"2"12;
"A"
$PN"1"19;
%"RES"
"1","(-1100,3025)","0","mstr_discrete","I52";
;
CDS_SEC"1"
CDS_LIB"mstr_discrete"
ROOM"VDDQ_KLM_PWR_VR"
CDS_LOCATION"R9L9"
SEC"1"
SEC_TYPE"0402"
VALUE"1.0"
TOLERANCE"1%"
WATTAGE"1/16W"
LOCATION"R9L9"
MATERIAL"CHIP"
PACK_TYPE"0402"
PART_NUMBER"G21796-090";
"B"
$PN"2"4;
"A"
$PN"1"43;
%"CAP_A"
"1","(-675,2425)","2","dev_discrete","I53";
;
CDS_LIB"dev_discrete"
CDS_LOCATION"C1A2"
ROOM"VDDQ_KLM_PWR_VR"
SEC"1"
SEC_TYPE"0402V"
CDS_SEC"1"
MATERIAL"X6S"
VOLTAGE"6.3V"
PACK_TYPE"0402V"
TOLERANCE"10%"
VALUE"1.0UF"
LOCATION"C1A2"
PART_NUMBER"D97712-004";
"B"
$PN"2"12;
"A"
$PN"1"4;
%"CAP"
"1","(-575,2425)","0","mstr_discrete","I54";
;
CDS_SEC"1"
CDS_LOCATION"C1B21"
CDS_LIB"mstr_discrete"
ROOM"VDDQ_KLM_PWR_VR"
SEC"1"
SEC_TYPE"0402"
MATERIAL"X7R"
VOLTAGE"16V"
PACK_TYPE"0402"
TOLERANCE"10%"
VALUE"0.22UF"
PART_NUMBER"A36096-155"
LOCATION"C1B21";
"A"
$PN"1"4;
"B"
$PN"2"12;
%"INDUCTOR"
"1","(3075,1850)","0","mstr_discrete","I55";
;
CDS_SEC"1"
ROOM"VDDQ_KLM_PWR_VR"
CDS_LOCATION"L1A2"
CDS_LIB"mstr_discrete"
SEC"1"
SEC_TYPE"SM"
LOCATION"L1A2"
VALUE"0.12UH"
PART_NUMBER"D92183-034"
MATERIAL"IND"
PACK_TYPE"SM";
"INA\NAC"
$PN"1"40;
"INB\NAC"
$PN"2"1;
%"CAP"
"1","(4025,1650)","0","mstr_discrete","I6";
;
CDS_SEC"1"
CDS_LOCATION"C1A12"
CDS_LIB"mstr_discrete"
VOLTAGE"4V"
ROOM"VDDQ_KLM_PWR_VR"
SEC"1"
SEC_TYPE"0805LF"
BOM_COST"VDDQ_KLM_PWR_VR"
MATERIAL"X6S"
PACK_TYPE"0805LF"
TOLERANCE"20%"
VALUE"22UF"
PART_NUMBER"C95333-002"
LOCATION"C1A12";
"A"
$PN"1"1;
"B"
$PN"2"15;
%"PVDDQ_KLM"
"1","(4025,-200)","0","mstr_symbols","I64";
;
HDL_POWER"PVDDQ_KLM"
BODY_TYPE"PLUMBING"
ROOM"VDDQ_KLM_PWR_VR"
CDS_LIB"mstr_symbols"
BOM_COST"VDDQ_KLM_PWR_VR"
VOLTAGE"1.2V";
"G\NAC"13;
%"INDUCTOR"
"1","(3150,-300)","0","mstr_discrete","I65";
;
CDS_SEC"1"
CDS_LIB"mstr_discrete"
SEC_TYPE"SM"
SEC"1"
CDS_LOCATION"L1A1"
ROOM"VDDQ_KLM_PWR_VR"
PART_NUMBER"D92183-034"
LOCATION"L1A1"
PACK_TYPE"SM"
MATERIAL"IND"
VALUE"0.12UH";
"INA\NAC"
$PN"1"21;
"INB\NAC"
$PN"2"13;
%"CAP"
"1","(4025,-500)","0","mstr_discrete","I68";
;
CDS_SEC"1"
SEC"1"
SEC_TYPE"0805LF"
BOM_COST"VDDQ_KLM_PWR_VR"
CDS_LOCATION"C1A1"
ROOM"VDDQ_KLM_PWR_VR"
VOLTAGE"4V"
CDS_LIB"mstr_discrete"
PART_NUMBER"C95333-002"
MATERIAL"X6S"
PACK_TYPE"0805LF"
LOCATION"C1A1"
VALUE"22UF"
TOLERANCE"20%";
"A"
$PN"1"13;
"B"
$PN"2"14;
%"GND"
"1","(4025,-725)","0","mstr_symbols","I69";
;
HDL_POWER"GND"
BODY_TYPE"PLUMBING"
SIZE"1B"
VOLTAGE"0"
CDS_LIB"mstr_symbols"
BOM_COST"VDDQ_KLM_PWR_VR"
ROOM"VDDQ_KLM_PWR_VR";
"A\NAC"14;
%"GND"
"1","(4025,1425)","0","mstr_symbols","I7";
;
HDL_POWER"GND"
BODY_TYPE"PLUMBING"
ROOM"VDDQ_KLM_PWR_VR"
CDS_LIB"mstr_symbols"
VOLTAGE"0"
BOM_COST"VDDQ_KLM_PWR_VR"
SIZE"1B";
"A\NAC"15;
%"GND"
"1","(2350,-750)","0","mstr_symbols","I70";
;
HDL_POWER"GND"
BODY_TYPE"PLUMBING"
CDS_LIB"mstr_symbols"
VOLTAGE"0"
SIZE"1B"
BOM_COST"VDDQ_KLM_PWR_VR"
ROOM"VDDQ_KLM_PWR_VR";
"A\NAC"16;
%"CAP"
"1","(-650,275)","0","mstr_discrete","I72";
;
CDS_SEC"1"
SEC"1"
SEC_TYPE"0402"
ROOM"VDDQ_KLM_PWR_VR"
CDS_LOCATION"C1A13"
CDS_LIB"mstr_discrete"
VOLTAGE"16V"
TOLERANCE"10%"
PART_NUMBER"A36096-155"
MATERIAL"X7R"
PACK_TYPE"0402"
LOCATION"C1A13"
VALUE"0.22UF";
"A"
$PN"1"20;
"B"
$PN"2"18;
%"CAP_A"
"1","(-750,275)","2","dev_discrete","I73";
;
CDS_LIB"dev_discrete"
ROOM"VDDQ_KLM_PWR_VR"
SEC_TYPE"0402V"
SEC"1"
CDS_LOCATION"C1A11"
CDS_SEC"1"
LOCATION"C1A11"
VALUE"1.0UF"
VOLTAGE"6.3V"
TOLERANCE"10%"
MATERIAL"X6S"
PACK_TYPE"0402V"
PART_NUMBER"D97712-004";
"B"
$PN"2"18;
"A"
$PN"1"20;
%"CAP"
"1","(-950,-325)","2","mstr_discrete","I75";
;
CDS_SEC"1"
CDS_LIB"mstr_discrete"
SPOF"TRUE"
SEC"1"
CDS_LOCATION"C1A8"
SEC_TYPE"0402"
ROOM"VDDQ_KLM_PWR_VR"
LOCATION"C1A8"
VALUE"0.220UF"
VOLTAGE"16V"
TOLERANCE"10%"
MATERIAL"X7R"
PACK_TYPE"0402"
PART_NUMBER"A36096-104";
"A"
$PN"1"33;
"B"
$PN"2"27;
%"RES"
"1","(-1050,825)","0","mstr_discrete","I76";
;
CDS_SEC"1"
SEC_TYPE"0402"
SEC"1"
ROOM"VDDQ_KLM_PWR_VR"
CDS_LOCATION"R9L4"
CDS_LIB"mstr_discrete"
LOCATION"R9L4"
MATERIAL"CHIP"
PACK_TYPE"0402"
TOLERANCE"1%"
PART_NUMBER"G21796-090"
VALUE"1.0"
WATTAGE"1/16W";
"B"
$PN"2"20;
"A"
$PN"1"22;
%"CAP"
"1","(-1275,300)","0","mstr_discrete","I77";
;
CDS_SEC"1"
SEC"1"
SEC_TYPE"0402"
ROOM"VDDQ_KLM_PWR_VR"
CDS_LIB"mstr_discrete"
CDS_LOCATION"C1A6"
MATERIAL"X6S"
VALUE"1.0UF"
TOLERANCE"10%"
VOLTAGE"16V"
LOCATION"C1A6"
PACK_TYPE"0402"
PART_NUMBER"D97712-011";
"A"
$PN"1"22;
"B"
$PN"2"18;
%"CAP_A"
"1","(-1750,275)","0","dev_discrete","I78";
;
SEC"1"
SEC_TYPE"0402V"
ROOM"VDDQ_KLM_PWR_VR"
CDS_SEC"1"
CDS_LOCATION"C1A20"
CDS_LIB"dev_discrete"
LOCATION"C1A20"
VALUE"0.1UF"
VOLTAGE"16V"
TOLERANCE"10%"
PART_NUMBER"A36096-030"
PACK_TYPE"0402V"
MATERIAL"X7R";
"B"
$PN"2"18;
"A"
$PN"1"17;
%"CAP"
"1","(-1975,275)","0","mstr_discrete","I79";
;
CDS_SEC"1"
SEC"1"
SEC_TYPE"0402"
ROOM"VDDQ_KLM_PWR_VR"
CDS_LOCATION"C1A9"
CDS_LIB"mstr_discrete"
VALUE"1.0UF"
LOCATION"C1A9"
VOLTAGE"16V"
TOLERANCE"10%"
PART_NUMBER"D97712-011"
MATERIAL"X6S"
PACK_TYPE"0402";
"A"
$PN"1"17;
"B"
$PN"2"18;
%"CAP"
"1","(-2225,275)","0","mstr_discrete","I80";
;
CDS_SEC"1"
SEC"1"
SEC_TYPE"0805"
ROOM"VDDQ_KLM_PWR_VR"
CDS_LOCATION"C9L5"
CDS_LIB"mstr_discrete"
LOCATION"C9L5"
VALUE"10UF"
VOLTAGE"16V"
TOLERANCE"10%"
PART_NUMBER"C95333-007"
PACK_TYPE"0805"
MATERIAL"X6S";
"A"
$PN"1"17;
"B"
$PN"2"18;
%"CAP"
"1","(-2475,225)","0","mstr_discrete","I81";
;
CDS_SEC"1"
SEC_TYPE"0805"
SEC"1"
CDS_LOCATION"C9L13"
ROOM"VDDQ_KLM_PWR_VR"
CDS_LIB"mstr_discrete"
LOCATION"C9L13"
VALUE"10UF"
VOLTAGE"16V"
PART_NUMBER"C95333-007"
TOLERANCE"10%"
PACK_TYPE"0805"
MATERIAL"X6S";
"A"
$PN"1"17;
"B"
$PN"2"18;
%"VCC_CORE"
"1","(-2725,750)","0","mstr_symbols","I83";
;
CDS_LIB"mstr_symbols"
HDL_POWER"VR_FET_SW_P12V_STBY_PVDDQ_KLM";
"A"17;
%"CAP"
"1","(-2725,275)","0","mstr_discrete","I84";
;
CDS_SEC"1"
SEC"1"
SEC_TYPE"0805"
ROOM"VDDQ_KLM_PWR_VR"
CDS_LOCATION"C9L14"
CDS_LIB"mstr_discrete"
LOCATION"C9L14"
VALUE"10UF"
VOLTAGE"16V"
TOLERANCE"10%"
PART_NUMBER"C95333-007"
PACK_TYPE"0805"
MATERIAL"X6S";
"A"
$PN"1"17;
"B"
$PN"2"18;
%"GND"
"1","(-2725,-175)","0","mstr_symbols","I85";
;
HDL_POWER"GND"
BODY_TYPE"PLUMBING"
SIZE"1B"
CDS_LIB"mstr_symbols"
VOLTAGE"0"
BOM_COST"VDDQ_KLM_PWR_VR"
ROOM"VDDQ_KLM_PWR_VR";
"A\NAC"18;
%"VCC_CORE"
"1","(-2650,2775)","0","mstr_symbols","I86";
;
CDS_LIB"mstr_symbols"
HDL_POWER"VR_FET_SW_P12V_STBY_PVDDQ_KLM";
"A"19;
%"P5V_STBY"
"1","(200,950)","0","mstr_symbols","I88";
;
HDL_POWER"P5V_STBY"
BODY_TYPE"PLUMBING"
SIZE"1B"
CDS_LIB"mstr_symbols"
VOLTAGE"5.0V";
"G\NAC"20;
END.
